# BASEBOARD_FAB2 (Tioga Pass) — schematic netlist excerpt (pin names and nets, part order shuffled) for the footprints in the layout excerpt that follows; sources: Cadence DE-HDL packaged netlist, KiCad conversion of Wiwynn_Tioga_Pass_MB.brd

C1L4  CAP_A  0.1UF 16V 10% X7R  pkg 0402V  page 175 : A = P5V_STBY ; B = GND
RN8F3  RES  4.75K 1% CHIP  pkg 0402  page 246 : A = P3V3_STBY ; B = PU_TPM_SPI_BMC_HOLD_N
C1M10  CAP  0.22UF 16V 10% X7R  pkg 0402  page 106 : A = P3E_CPU0_PE3_OCP_TXP<13> ; B = P3E_OCP_CPU0_PE3_C_TXP<13>

(kicad_pcb
	(version 20260206)
	(generator "pcbnew")
	(generator_version "10.0")
	(general
		(thickness 1.6)
		(legacy_teardrops no)
	)
	(paper "A4")
	(title_block
		(title "Wiwynn_Tioga_Pass_MB.brd")
		(comment 1 "Tioga Pass / footprints 3780-3782 of 4770")
	)
	(layers
		(0 "F.Cu" signal "TOP")
		(4 "In1.Cu" signal "L2GND")
		(6 "In2.Cu" signal "L3")
		(8 "In3.Cu" signal "L4GND")
		(10 "In4.Cu" signal "L5")
		(12 "In5.Cu" signal "L6GND")
		(14 "In6.Cu" signal "L7VCC")
		(16 "In7.Cu" signal "L8VCC")
		(18 "In8.Cu" signal "L9GND")
		(20 "In9.Cu" signal "L10")
		(22 "In10.Cu" signal "L11GND")
		(24 "In11.Cu" signal "L12")
		(26 "In12.Cu" signal "L13GND")
		(2 "B.Cu" signal "BOTTOM")
		(9 "F.Adhes" user "F.Adhesive")
		(11 "B.Adhes" user "B.Adhesive")
		(13 "F.Paste" user "Package Geometry/Pastemask Top")
		(15 "B.Paste" user "Package Geometry/Pastemask Bottom")
		(5 "F.SilkS" user "Ref Des/Silkscreen Top")
		(7 "B.SilkS" user "Ref Des/Silkscreen Bottom")
		(1 "F.Mask" user "Board Geometry/Soldermask Top")
		(3 "B.Mask" user "Board Geometry/Soldermask Bottom")
		(17 "Dwgs.User" user "User.Drawings")
		(19 "Cmts.User" user "User.Comments")
		(21 "Eco1.User" user "User.Eco1")
		(23 "Eco2.User" user "User.Eco2")
		(25 "Edge.Cuts" user "Board Geometry/Outline")
		(27 "Margin" user)
		(31 "F.CrtYd" user "Package Geometry/Place Bound Top")
		(29 "B.CrtYd" user "Package Geometry/Place Bound Bottom")
		(35 "F.Fab" user "Ref Des/Assembly Top")
		(33 "B.Fab" user "Ref Des/Assembly Bottom")
	)
	(footprint ""
		(layer "B.Cu")
		(at 459.867 -116.49202)
		(property "Reference" "C1M10"
			(at 0 0 0)
			(layer "B.SilkS")
			(hide yes)
			(effects
				(font
					(size 1.27 1.27)
				)
				(justify mirror)
			)
		)
		(property "Value" ""
			(at 0 0 0)
			(layer "B.Fab")
			(effects
				(font
					(size 1.27 1.27)
				)
				(justify mirror)
			)
		)
		(duplicate_pad_numbers_are_jumpers no)
		(fp_rect
			(start -0.3048 0.9906)
			(end 0.3048 -0.1016)
			(stroke
				(width 0)
				(type default)
			)
			(fill no)
			(layer "B.CrtYd")
		)
		(fp_line
			(start -0.3048 -0.1016)
			(end 0.3048 -0.1016)
			(stroke
				(width 0.1)
				(type default)
			)
			(layer "B.Fab")
		)
		(fp_line
			(start -0.3048 0.9906)
			(end -0.3048 -0.1016)
			(stroke
				(width 0.1)
				(type default)
			)
			(layer "B.Fab")
		)
		(fp_line
			(start 0.3048 -0.1016)
			(end 0.3048 0.9906)
			(stroke
				(width 0.1)
				(type default)
			)
			(layer "B.Fab")
		)
		(fp_line
			(start 0.3048 0.9906)
			(end -0.3048 0.9906)
			(stroke
				(width 0.1)
				(type default)
			)
			(layer "B.Fab")
		)
		(pad "1" smd rect
			(at 0 0 180)
			(size 0.508 0.508)
			(layers "B.Cu" "B.Mask" "B.Paste")
			(net "P3E_CPU0_PE3_OCP_TXP<13>")
		)
		(pad "2" smd rect
			(at 0 0.889 180)
			(size 0.508 0.508)
			(layers "B.Cu" "B.Mask" "B.Paste")
			(net "P3E_OCP_CPU0_PE3_C_TXP<13>")
		)
		(zone
			(layer "B.Cu")
			(hatch none 0.5)
			(connect_pads
				(clearance 0)
			)
			(min_thickness 0.25)
			(keepout
				(tracks allowed)
				(vias not_allowed)
				(pads allowed)
				(copperpour not_allowed)
				(footprints allowed)
			)
			(placement
				(enabled no)
				(sheetname "")
			)
			(fill
				(thermal_gap 0.5)
				(thermal_bridge_width 0.5)
				(island_removal_mode 0)
			)
			(polygon
				(pts
					(xy 459.613 -115.85702) (xy 460.121 -115.85702) (xy 460.121 -116.23802) (xy 459.613 -116.23802)
				)
			)
		)
		(zone
			(layer "B.Cu")
			(hatch none 0.5)
			(connect_pads
				(clearance 0)
			)
			(min_thickness 0.25)
			(keepout
				(tracks not_allowed)
				(vias allowed)
				(pads allowed)
				(copperpour not_allowed)
				(footprints allowed)
			)
			(placement
				(enabled no)
				(sheetname "")
			)
			(fill
				(thermal_gap 0.5)
				(thermal_bridge_width 0.5)
				(island_removal_mode 0)
			)
			(polygon
				(pts
					(xy 459.613 -115.85702) (xy 460.121 -115.85702) (xy 460.121 -116.23802) (xy 459.613 -116.23802)
				)
			)
		)
	)
	(footprint ""
		(layer "B.Cu")
		(at 377.698 -19.558)
		(property "Reference" "RN8F3"
			(at 0.8382 -0.67818 0)
			(unlocked yes)
			(layer "B.SilkS")
			(effects
				(font
					(size 0.4064 0.254)
					(thickness 0.1524)
				)
				(justify left mirror)
			)
		)
		(property "Value" ""
			(at 0 0 0)
			(layer "B.Fab")
			(effects
				(font
					(size 1.27 1.27)
				)
				(justify mirror)
			)
		)
		(duplicate_pad_numbers_are_jumpers no)
		(fp_poly
			(pts
				(xy 0.2794 -0.1016) (xy -0.2794 -0.1016) (xy -0.2794 0.9906) (xy 0.2794 0.9906)
			)
			(stroke
				(width 0)
				(type default)
			)
			(fill no)
			(layer "B.CrtYd")
		)
		(fp_line
			(start -0.2794 -0.1016)
			(end 0.2794 -0.1016)
			(stroke
				(width 0.1)
				(type default)
			)
			(layer "B.Fab")
		)
		(fp_line
			(start -0.2794 0.9906)
			(end -0.2794 -0.1016)
			(stroke
				(width 0.1)
				(type default)
			)
			(layer "B.Fab")
		)
		(fp_line
			(start 0.2794 -0.1016)
			(end 0.2794 0.9906)
			(stroke
				(width 0.1)
				(type default)
			)
			(layer "B.Fab")
		)
		(fp_line
			(start 0.2794 0.9906)
			(end -0.2794 0.9906)
			(stroke
				(width 0.1)
				(type default)
			)
			(layer "B.Fab")
		)
		(pad "1" smd rect
			(at 0 0 180)
			(size 0.508 0.508)
			(layers "B.Cu" "B.Mask" "B.Paste")
			(net "P3V3_STBY")
		)
		(pad "2" smd rect
			(at 0 0.889 180)
			(size 0.508 0.508)
			(layers "B.Cu" "B.Mask" "B.Paste")
			(net "PU_TPM_SPI_BMC_HOLD_N")
		)
		(zone
			(layer "B.Cu")
			(hatch none 0.5)
			(connect_pads
				(clearance 0)
			)
			(min_thickness 0.25)
			(keepout
				(tracks allowed)
				(vias not_allowed)
				(pads allowed)
				(copperpour not_allowed)
				(footprints allowed)
			)
			(placement
				(enabled no)
				(sheetname "")
			)
			(fill
				(thermal_gap 0.5)
				(thermal_bridge_width 0.5)
				(island_removal_mode 0)
			)
			(polygon
				(pts
					(xy 377.952 -19.304) (xy 377.444 -19.304) (xy 377.444 -18.923) (xy 377.952 -18.923)
				)
			)
		)
		(zone
			(layer "B.Cu")
			(hatch none 0.5)
			(connect_pads
				(clearance 0)
			)
			(min_thickness 0.25)
			(keepout
				(tracks not_allowed)
				(vias allowed)
				(pads allowed)
				(copperpour not_allowed)
				(footprints allowed)
			)
			(placement
				(enabled no)
				(sheetname "")
			)
			(fill
				(thermal_gap 0.5)
				(thermal_bridge_width 0.5)
				(island_removal_mode 0)
			)
			(polygon
				(pts
					(xy 377.952 -18.923) (xy 377.444 -18.923) (xy 377.444 -19.304) (xy 377.952 -19.304)
				)
			)
		)
	)
	(footprint ""
		(layer "B.Cu")
		(at 487.9975 -152.5016 -90)
		(property "Reference" "C1L4"
			(at 0 0 90)
			(layer "B.SilkS")
			(hide yes)
			(effects
				(font
					(size 1.27 1.27)
				)
				(justify mirror)
			)
		)
		(property "Value" ""
			(at 0 0 90)
			(layer "B.Fab")
			(effects
				(font
					(size 1.27 1.27)
				)
				(justify mirror)
			)
		)
		(duplicate_pad_numbers_are_jumpers no)
		(fp_poly
			(pts
				(xy -0.3048 -0.1016) (xy -0.3048 0.9906) (xy 0.3048 0.9906) (xy 0.3048 -0.1016)
			)
			(stroke
				(width 0)
				(type default)
			)
			(fill no)
			(layer "B.CrtYd")
		)
		(fp_line
			(start -0.3048 0.9906)
			(end -0.3048 -0.1016)
			(stroke
				(width 0.1)
				(type default)
			)
			(layer "B.Fab")
		)
		(fp_line
			(start 0.3048 0.9906)
			(end -0.3048 0.9906)
			(stroke
				(width 0.1)
				(type default)
			)
			(layer "B.Fab")
		)
		(fp_line
			(start -0.3048 -0.1016)
			(end 0.3048 -0.1016)
			(stroke
				(width 0.1)
				(type default)
			)
			(layer "B.Fab")
		)
		(fp_line
			(start 0.3048 -0.1016)
			(end 0.3048 0.9906)
			(stroke
				(width 0.1)
				(type default)
			)
			(layer "B.Fab")
		)
		(pad "1" smd rect
			(at 0 0 90)
			(size 0.508 0.508)
			(layers "B.Cu" "B.Mask" "B.Paste")
			(net "P5V_STBY")
		)
		(pad "2" smd rect
			(at 0 0.889 90)
			(size 0.508 0.508)
			(layers "B.Cu" "B.Mask" "B.Paste")
			(net "GND")
		)
		(zone
			(layer "B.Cu")
			(hatch none 0.5)
			(connect_pads
				(clearance 0)
			)
			(min_thickness 0.25)
			(keepout
				(tracks not_allowed)
				(vias allowed)
				(pads allowed)
				(copperpour not_allowed)
				(footprints allowed)
			)
			(placement
				(enabled no)
				(sheetname "")
			)
			(fill
				(thermal_gap 0.5)
				(thermal_bridge_width 0.5)
				(island_removal_mode 0)
			)
			(polygon
				(pts
					(xy 487.3625 -152.2476) (xy 487.3625 -152.7556) (xy 487.7435 -152.7556) (xy 487.7435 -152.2476)
				)
			)
		)
		(zone
			(layer "B.Cu")
			(hatch none 0.5)
			(connect_pads
				(clearance 0)
			)
			(min_thickness 0.25)
			(keepout
				(tracks allowed)
				(vias not_allowed)
				(pads allowed)
				(copperpour not_allowed)
				(footprints allowed)
			)
			(placement
				(enabled no)
				(sheetname "")
			)
			(fill
				(thermal_gap 0.5)
				(thermal_bridge_width 0.5)
				(island_removal_mode 0)
			)
			(polygon
				(pts
					(xy 487.7435 -152.2476) (xy 487.7435 -152.7556) (xy 487.3625 -152.7556) (xy 487.3625 -152.2476)
				)
			)
		)
	)
)
